# S9S_MB_2U (Grand Teton) — schematic netlist excerpt (pin names and nets, part order shuffled) for the footprints in the layout excerpt that follows; sources: Cadence DE-HDL packaged netlist, KiCad conversion of 03242023_DA0F0TMBIJ0_F0T_Motherboard_J_brd_V01_OCP.brd

R710  Q_RES  1K 1% CHIP  pkg 0402LF  page 243 : A = PD_MB_FRU_WP ; B = GND
R2386  Q_RES  100 1% EMPTY  pkg 0402LF  page 274 : A = PVNN_TERM_CPU0 ; B = SVID_DIO0_CPU0_R

(kicad_pcb
	(version 20260206)
	(generator "pcbnew")
	(generator_version "10.0")
	(general
		(thickness 1.6)
		(legacy_teardrops no)
	)
	(paper "A4")
	(title_block
		(title "03242023_DA0F0TMBIJ0_F0T_Motherboard_J_brd_V01_OCP.brd")
		(comment 1 "Grand Teton / footprints 769-770 of 6105")
	)
	(layers
		(0 "F.Cu" signal "TOP")
		(4 "In1.Cu" signal "GND")
		(6 "In2.Cu" signal "IN1")
		(8 "In3.Cu" signal "GND1")
		(10 "In4.Cu" signal "IN2")
		(12 "In5.Cu" signal "GND2")
		(14 "In6.Cu" signal "IN3")
		(16 "In7.Cu" signal "GND3")
		(18 "In8.Cu" signal "VCC")
		(20 "In9.Cu" signal "VCC1")
		(22 "In10.Cu" signal "GND4")
		(24 "In11.Cu" signal "IN4")
		(26 "In12.Cu" signal "GND5")
		(28 "In13.Cu" signal "IN5")
		(30 "In14.Cu" signal "GND6")
		(32 "In15.Cu" signal "IN6")
		(34 "In16.Cu" signal "GND7")
		(2 "B.Cu" signal "BOTTOM")
		(9 "F.Adhes" user "F.Adhesive")
		(11 "B.Adhes" user "B.Adhesive")
		(13 "F.Paste" user "Package Geometry/Pastemask Top")
		(15 "B.Paste" user "Package Geometry/Pastemask Bottom")
		(5 "F.SilkS" user "Ref Des/Silkscreen Top")
		(7 "B.SilkS" user "Ref Des/Silkscreen Bottom")
		(1 "F.Mask" user "Board Geometry/Soldermask Top")
		(3 "B.Mask" user "Board Geometry/Soldermask Bottom")
		(17 "Dwgs.User" user "User.Drawings")
		(19 "Cmts.User" user "User.Comments")
		(21 "Eco1.User" user "User.Eco1")
		(23 "Eco2.User" user "User.Eco2")
		(25 "Edge.Cuts" user "Board Geometry/Outline")
		(27 "Margin" user)
		(31 "F.CrtYd" user "Package Geometry/Place Bound Top")
		(29 "B.CrtYd" user "Package Geometry/Place Bound Bottom")
		(35 "F.Fab" user "Ref Des/Assembly Top")
		(33 "B.Fab" user "Ref Des/Assembly Bottom")
	)
	(footprint ""
		(layer "F.Cu")
		(at 432.80584 -138.557762 -90)
		(property "Reference" "R2386"
			(at 0 0 270)
			(layer "F.SilkS")
			(hide yes)
			(effects
				(font
					(size 1.27 1.27)
				)
			)
		)
		(property "Value" ""
			(at 0 0 270)
			(layer "F.Fab")
			(effects
				(font
					(size 1.27 1.27)
				)
			)
		)
		(duplicate_pad_numbers_are_jumpers no)
		(fp_line
			(start -0.7874 0.4064)
			(end -0.7874 -0.4064)
			(stroke
				(width 0.1524)
				(type default)
			)
			(layer "F.SilkS")
		)
		(fp_line
			(start 0.7874 0.4064)
			(end -0.7874 0.4064)
			(stroke
				(width 0.1524)
				(type default)
			)
			(layer "F.SilkS")
		)
		(fp_line
			(start -0.7874 -0.4064)
			(end 0.7874 -0.4064)
			(stroke
				(width 0.1524)
				(type default)
			)
			(layer "F.SilkS")
		)
		(fp_line
			(start 0.7874 -0.4064)
			(end 0.7874 0.4064)
			(stroke
				(width 0.1524)
				(type default)
			)
			(layer "F.SilkS")
		)
		(fp_line
			(start -0.67945 0.3048)
			(end -0.67945 -0.305054)
			(stroke
				(width 0.1)
				(type default)
			)
			(layer "F.Fab")
		)
		(fp_line
			(start -0.12065 0.3048)
			(end -0.67945 0.3048)
			(stroke
				(width 0.1)
				(type default)
			)
			(layer "F.Fab")
		)
		(fp_line
			(start 0.120396 0.3048)
			(end 0.120396 0.2794)
			(stroke
				(width 0.1)
				(type default)
			)
			(layer "F.Fab")
		)
		(fp_line
			(start 0.67945 0.3048)
			(end 0.120396 0.3048)
			(stroke
				(width 0.1)
				(type default)
			)
			(layer "F.Fab")
		)
		(fp_line
			(start -0.12065 0.2794)
			(end -0.12065 0.3048)
			(stroke
				(width 0.1)
				(type default)
			)
			(layer "F.Fab")
		)
		(fp_line
			(start 0.120396 0.2794)
			(end -0.12065 0.2794)
			(stroke
				(width 0.1)
				(type default)
			)
			(layer "F.Fab")
		)
		(fp_line
			(start -0.12065 -0.2794)
			(end 0.12065 -0.2794)
			(stroke
				(width 0.1)
				(type default)
			)
			(layer "F.Fab")
		)
		(fp_line
			(start 0.12065 -0.2794)
			(end 0.12065 -0.3048)
			(stroke
				(width 0.1)
				(type default)
			)
			(layer "F.Fab")
		)
		(fp_line
			(start 0.12065 -0.3048)
			(end 0.67945 -0.3048)
			(stroke
				(width 0.1)
				(type default)
			)
			(layer "F.Fab")
		)
		(fp_line
			(start 0.67945 -0.3048)
			(end 0.67945 0.3048)
			(stroke
				(width 0.1)
				(type default)
			)
			(layer "F.Fab")
		)
		(fp_line
			(start -0.67945 -0.305054)
			(end -0.12065 -0.305054)
			(stroke
				(width 0.1)
				(type default)
			)
			(layer "F.Fab")
		)
		(fp_line
			(start -0.12065 -0.305054)
			(end -0.12065 -0.2794)
			(stroke
				(width 0.1)
				(type default)
			)
			(layer "F.Fab")
		)
		(pad "1" smd circle
			(at -0.40005 0 270)
			(size 0 0)
			(layers "F.Cu" "F.Mask" "F.Paste")
			(net "PVNN_TERM_CPU0")
		)
		(pad "2" smd circle
			(at 0.40005 0 270)
			(size 0 0)
			(layers "F.Cu" "F.Mask" "F.Paste")
			(net "SVID_DIO0_CPU0_R")
		)
	)
	(footprint ""
		(layer "F.Cu")
		(at 292.61054 -94.800674)
		(property "Reference" "R710"
			(at 0 0 0)
			(layer "F.SilkS")
			(hide yes)
			(effects
				(font
					(size 1.27 1.27)
				)
			)
		)
		(property "Value" ""
			(at 0 0 0)
			(layer "F.Fab")
			(effects
				(font
					(size 1.27 1.27)
				)
			)
		)
		(duplicate_pad_numbers_are_jumpers no)
		(fp_line
			(start -0.7874 -0.4064)
			(end 0.7874 -0.4064)
			(stroke
				(width 0.1524)
				(type default)
			)
			(layer "F.SilkS")
		)
		(fp_line
			(start -0.7874 0.4064)
			(end -0.7874 -0.4064)
			(stroke
				(width 0.1524)
				(type default)
			)
			(layer "F.SilkS")
		)
		(fp_line
			(start 0.7874 -0.4064)
			(end 0.7874 0.4064)
			(stroke
				(width 0.1524)
				(type default)
			)
			(layer "F.SilkS")
		)
		(fp_line
			(start 0.7874 0.4064)
			(end -0.7874 0.4064)
			(stroke
				(width 0.1524)
				(type default)
			)
			(layer "F.SilkS")
		)
		(fp_line
			(start -0.67945 -0.305054)
			(end -0.12065 -0.305054)
			(stroke
				(width 0.1)
				(type default)
			)
			(layer "F.Fab")
		)
		(fp_line
			(start -0.67945 0.3048)
			(end -0.67945 -0.305054)
			(stroke
				(width 0.1)
				(type default)
			)
			(layer "F.Fab")
		)
		(fp_line
			(start -0.12065 -0.305054)
			(end -0.12065 -0.2794)
			(stroke
				(width 0.1)
				(type default)
			)
			(layer "F.Fab")
		)
		(fp_line
			(start -0.12065 -0.2794)
			(end 0.12065 -0.2794)
			(stroke
				(width 0.1)
				(type default)
			)
			(layer "F.Fab")
		)
		(fp_line
			(start -0.12065 0.2794)
			(end -0.12065 0.3048)
			(stroke
				(width 0.1)
				(type default)
			)
			(layer "F.Fab")
		)
		(fp_line
			(start -0.12065 0.3048)
			(end -0.67945 0.3048)
			(stroke
				(width 0.1)
				(type default)
			)
			(layer "F.Fab")
		)
		(fp_line
			(start 0.120396 0.2794)
			(end -0.12065 0.2794)
			(stroke
				(width 0.1)
				(type default)
			)
			(layer "F.Fab")
		)
		(fp_line
			(start 0.120396 0.3048)
			(end 0.120396 0.2794)
			(stroke
				(width 0.1)
				(type default)
			)
			(layer "F.Fab")
		)
		(fp_line
			(start 0.12065 -0.3048)
			(end 0.67945 -0.3048)
			(stroke
				(width 0.1)
				(type default)
			)
			(layer "F.Fab")
		)
		(fp_line
			(start 0.12065 -0.2794)
			(end 0.12065 -0.3048)
			(stroke
				(width 0.1)
				(type default)
			)
			(layer "F.Fab")
		)
		(fp_line
			(start 0.67945 -0.3048)
			(end 0.67945 0.3048)
			(stroke
				(width 0.1)
				(type default)
			)
			(layer "F.Fab")
		)
		(fp_line
			(start 0.67945 0.3048)
			(end 0.120396 0.3048)
			(stroke
				(width 0.1)
				(type default)
			)
			(layer "F.Fab")
		)
		(pad "1" smd circle
			(at -0.40005 0)
			(size 0 0)
			(layers "F.Cu" "F.Mask" "F.Paste")
			(net "PD_MB_FRU_WP")
		)
		(pad "2" smd circle
			(at 0.40005 0)
			(size 0 0)
			(layers "F.Cu" "F.Mask" "F.Paste")
			(net "GND")
		)
	)
)
